# BASEBOARD_FAB2 (Tioga Pass) — schematic netlist excerpt (pin names and nets, part order shuffled) for the footprints in the layout excerpt that follows; sources: Cadence DE-HDL packaged netlist, KiCad conversion of Wiwynn_Tioga_Pass_MB.brd

EU3P1  PXE1110B  IC  pkg QFN  page 211
  DNC(0)  = NC
  DNC(1)  = NC
  BPWM1  = NC
  DNC(2)  = NC
  APWM1  = VR_PVCCIO_CPU0_PWM1
  SDA  = SMB_VR_STBY_LVC3_SDA
  SCL  = SMB_VR_STBY_LVC3_SCL
  RESET_N  = NC
  AVRRDY  = PWRGD_PVCCIO_CPU0_R
  AVREN  = VR_PVCCIO_CPU0_EN
  VRHOT_N  = IRQ_PVCCIO_CPU0_VRHOT_N
  PINALRT_N  = NC
  MP0  = NC
  MP1  = NC
  VCLK  = SVID_CLK_PVCCIO_CPU0
  VDIO  = SVID_VDIO_PVCCIO_CPU0
  VALRT_N  = SVID_ALERT_PVCCIO_CPU0
  MP2  = NC
  AVSEN  = VR_PVCCIO_CPU0_AVSP
  AVREF  = VSENSE_PVCCIO_CPU0_AVSN
  AIREF1  = VR_PVCCIO_CPU0_AIREF1
  AISEN1  = ISENSE_PVCCIO_CPU0_PH1_IMON
  GND(1)  = GND
  DNC(3)  = NC
  BIREF1  = NC
  BISEN1  = GND
  GND(0)  = GND
  DNC(4)  = NC
  BVSEN  = NC
  BVREF  = NC
  MP3  = NC
  MP4  = PU_VR_PVCCIO_CPU0_FAULT1
  XADDR2  = VR_PVCCIO_CPU0_XADDR2
  BTSEN  = NC
  ATSEN  = A_TSENSE_PVCCIO_CPU0
  XADDR1  = VR_PVCCIO_CPU0_XADDR1
  VINSEN  = VR_PVCCIO_CPU0_VINSEN
  IINSEN  = NC
  VDD  = VR_PVCCIO_CPU0_VDD
  VD12  = VR_PVCCIO_CPU0_VD12
  THPAD  = GND

(kicad_pcb
	(version 20260206)
	(generator "pcbnew")
	(generator_version "10.0")
	(general
		(thickness 1.6)
		(legacy_teardrops no)
	)
	(paper "A4")
	(title_block
		(title "Wiwynn_Tioga_Pass_MB.brd")
		(comment 1 "Tioga Pass / footprint 3922 of 4770 (EU3P1), pads 18-34 of 41")
	)
	(layers
		(0 "F.Cu" signal "TOP")
		(4 "In1.Cu" signal "L2GND")
		(6 "In2.Cu" signal "L3")
		(8 "In3.Cu" signal "L4GND")
		(10 "In4.Cu" signal "L5")
		(12 "In5.Cu" signal "L6GND")
		(14 "In6.Cu" signal "L7VCC")
		(16 "In7.Cu" signal "L8VCC")
		(18 "In8.Cu" signal "L9GND")
		(20 "In9.Cu" signal "L10")
		(22 "In10.Cu" signal "L11GND")
		(24 "In11.Cu" signal "L12")
		(26 "In12.Cu" signal "L13GND")
		(2 "B.Cu" signal "BOTTOM")
		(9 "F.Adhes" user "F.Adhesive")
		(11 "B.Adhes" user "B.Adhesive")
		(13 "F.Paste" user "Package Geometry/Pastemask Top")
		(15 "B.Paste" user "Package Geometry/Pastemask Bottom")
		(5 "F.SilkS" user "Ref Des/Silkscreen Top")
		(7 "B.SilkS" user "Ref Des/Silkscreen Bottom")
		(1 "F.Mask" user "Board Geometry/Soldermask Top")
		(3 "B.Mask" user "Board Geometry/Soldermask Bottom")
		(17 "Dwgs.User" user "User.Drawings")
		(19 "Cmts.User" user "User.Comments")
		(21 "Eco1.User" user "User.Eco1")
		(23 "Eco2.User" user "User.Eco2")
		(25 "Edge.Cuts" user "Board Geometry/Outline")
		(27 "Margin" user)
		(31 "F.CrtYd" user "Package Geometry/Place Bound Top")
		(29 "B.CrtYd" user "Package Geometry/Place Bound Bottom")
		(35 "F.Fab" user "Ref Des/Assembly Top")
		(33 "B.Fab" user "Ref Des/Assembly Bottom")
	)
	(footprint ""
		(layer "B.Cu")
		(at 346.5322 -87.4522 -90)
		(property "Reference" "EU3P1"
			(at -1.80975 3.2893 0)
			(unlocked yes)
			(layer "B.SilkS")
			(effects
				(font
					(size 0.7874 0.5842)
					(thickness 0.1524)
				)
				(justify left mirror)
			)
		)
		(property "Value" ""
			(at 0 0 90)
			(layer "B.Fab")
			(effects
				(font
					(size 1.27 1.27)
				)
				(justify mirror)
			)
		)
		(duplicate_pad_numbers_are_jumpers no)
		(pad "18" smd custom
			(at -0.999998 2.4511 90)
			(size 0.0508 0.0508)
			(layers "B.Cu" "B.Mask" "B.Paste")
			(net "Net_300")
			(options
				(clearance outline)
				(anchor circle)
			)
			(primitives
				(gr_poly
					(pts
						(arc
							(start -0.1016 0.254)
							(mid 0 0.3556)
							(end 0.1016 0.254)
						)
						(xy 0.1016 -0.3556) (xy -0.1016 -0.3556)
					)
					(width 0)
					(fill yes)
				)
			)
		)
		(pad "19" smd custom
			(at -1.400048 2.4511 90)
			(size 0.0508 0.0508)
			(layers "B.Cu" "B.Mask" "B.Paste")
			(net "VR_PVCCIO_CPU0_AVSP")
			(options
				(clearance outline)
				(anchor circle)
			)
			(primitives
				(gr_poly
					(pts
						(arc
							(start -0.1016 0.254)
							(mid 0 0.3556)
							(end 0.1016 0.254)
						)
						(xy 0.1016 -0.3556) (xy -0.1016 -0.3556)
					)
					(width 0)
					(fill yes)
				)
			)
		)
		(pad "20" smd custom
			(at -1.800098 2.4511 90)
			(size 0.0508 0.0508)
			(layers "B.Cu" "B.Mask" "B.Paste")
			(net "VSENSE_PVCCIO_CPU0_AVSN")
			(options
				(clearance outline)
				(anchor circle)
			)
			(primitives
				(gr_poly
					(pts
						(arc
							(start -0.1016 0.254)
							(mid 0 0.3556)
							(end 0.1016 0.254)
						)
						(xy 0.1016 -0.3556) (xy -0.1016 -0.3556)
					)
					(width 0)
					(fill yes)
				)
			)
		)
		(pad "21" smd custom
			(at -2.4511 1.800098 90)
			(size 0.0508 0.0508)
			(layers "B.Cu" "B.Mask" "B.Paste")
			(net "VR_PVCCIO_CPU0_AIREF1")
			(options
				(clearance outline)
				(anchor circle)
			)
			(primitives
				(gr_poly
					(pts
						(arc
							(start -0.254 -0.1016)
							(mid -0.3556 0)
							(end -0.254 0.1016)
						)
						(xy 0.3556 0.1016) (xy 0.3556 -0.1016)
					)
					(width 0)
					(fill yes)
				)
			)
		)
		(pad "22" smd custom
			(at -2.4511 1.400048 90)
			(size 0.0508 0.0508)
			(layers "B.Cu" "B.Mask" "B.Paste")
			(net "ISENSE_PVCCIO_CPU0_PH1_IMON")
			(options
				(clearance outline)
				(anchor circle)
			)
			(primitives
				(gr_poly
					(pts
						(arc
							(start -0.254 -0.1016)
							(mid -0.3556 0)
							(end -0.254 0.1016)
						)
						(xy 0.3556 0.1016) (xy 0.3556 -0.1016)
					)
					(width 0)
					(fill yes)
				)
			)
		)
		(pad "23" smd custom
			(at -2.4511 0.999998 90)
			(size 0.0508 0.0508)
			(layers "B.Cu" "B.Mask" "B.Paste")
			(net "GND")
			(options
				(clearance outline)
				(anchor circle)
			)
			(primitives
				(gr_poly
					(pts
						(arc
							(start -0.254 -0.1016)
							(mid -0.3556 0)
							(end -0.254 0.1016)
						)
						(xy 0.3556 0.1016) (xy 0.3556 -0.1016)
					)
					(width 0)
					(fill yes)
				)
			)
		)
		(pad "24" smd custom
			(at -2.4511 0.599948 90)
			(size 0.0508 0.0508)
			(layers "B.Cu" "B.Mask" "B.Paste")
			(net "Net_334")
			(options
				(clearance outline)
				(anchor circle)
			)
			(primitives
				(gr_poly
					(pts
						(arc
							(start -0.254 -0.1016)
							(mid -0.3556 0)
							(end -0.254 0.1016)
						)
						(xy 0.3556 0.1016) (xy 0.3556 -0.1016)
					)
					(width 0)
					(fill yes)
				)
			)
		)
		(pad "25" smd custom
			(at -2.4511 0.199898 90)
			(size 0.0508 0.0508)
			(layers "B.Cu" "B.Mask" "B.Paste")
			(net "Net_251")
			(options
				(clearance outline)
				(anchor circle)
			)
			(primitives
				(gr_poly
					(pts
						(arc
							(start -0.254 -0.1016)
							(mid -0.3556 0)
							(end -0.254 0.1016)
						)
						(xy 0.3556 0.1016) (xy 0.3556 -0.1016)
					)
					(width 0)
					(fill yes)
				)
			)
		)
		(pad "26" smd custom
			(at -2.4511 -0.199898 90)
			(size 0.0508 0.0508)
			(layers "B.Cu" "B.Mask" "B.Paste")
			(net "GND")
			(options
				(clearance outline)
				(anchor circle)
			)
			(primitives
				(gr_poly
					(pts
						(arc
							(start -0.254 -0.1016)
							(mid -0.3556 0)
							(end -0.254 0.1016)
						)
						(xy 0.3556 0.1016) (xy 0.3556 -0.1016)
					)
					(width 0)
					(fill yes)
				)
			)
		)
		(pad "27" smd custom
			(at -2.4511 -0.599948 90)
			(size 0.0508 0.0508)
			(layers "B.Cu" "B.Mask" "B.Paste")
			(net "GND")
			(options
				(clearance outline)
				(anchor circle)
			)
			(primitives
				(gr_poly
					(pts
						(arc
							(start -0.254 -0.1016)
							(mid -0.3556 0)
							(end -0.254 0.1016)
						)
						(xy 0.3556 0.1016) (xy 0.3556 -0.1016)
					)
					(width 0)
					(fill yes)
				)
			)
		)
		(pad "28" smd custom
			(at -2.4511 -0.999998 90)
			(size 0.0508 0.0508)
			(layers "B.Cu" "B.Mask" "B.Paste")
			(net "Net_335")
			(options
				(clearance outline)
				(anchor circle)
			)
			(primitives
				(gr_poly
					(pts
						(arc
							(start -0.254 -0.1016)
							(mid -0.3556 0)
							(end -0.254 0.1016)
						)
						(xy 0.3556 0.1016) (xy 0.3556 -0.1016)
					)
					(width 0)
					(fill yes)
				)
			)
		)
		(pad "29" smd custom
			(at -2.4511 -1.400048 90)
			(size 0.0508 0.0508)
			(layers "B.Cu" "B.Mask" "B.Paste")
			(net "Net_254")
			(options
				(clearance outline)
				(anchor circle)
			)
			(primitives
				(gr_poly
					(pts
						(arc
							(start -0.254 -0.1016)
							(mid -0.3556 0)
							(end -0.254 0.1016)
						)
						(xy 0.3556 0.1016) (xy 0.3556 -0.1016)
					)
					(width 0)
					(fill yes)
				)
			)
		)
		(pad "30" smd custom
			(at -2.4511 -1.800098 90)
			(size 0.0508 0.0508)
			(layers "B.Cu" "B.Mask" "B.Paste")
			(net "Net_253")
			(options
				(clearance outline)
				(anchor circle)
			)
			(primitives
				(gr_poly
					(pts
						(arc
							(start -0.254 -0.1016)
							(mid -0.3556 0)
							(end -0.254 0.1016)
						)
						(xy 0.3556 0.1016) (xy 0.3556 -0.1016)
					)
					(width 0)
					(fill yes)
				)
			)
		)
		(pad "31" smd custom
			(at -1.800098 -2.4511 90)
			(size 0.0508 0.0508)
			(layers "B.Cu" "B.Mask" "B.Paste")
			(net "Net_301")
			(options
				(clearance outline)
				(anchor circle)
			)
			(primitives
				(gr_poly
					(pts
						(arc
							(start 0.1016 -0.254)
							(mid 0 -0.3556)
							(end -0.1016 -0.254)
						)
						(xy -0.1016 0.3556) (xy 0.1016 0.3556)
					)
					(width 0)
					(fill yes)
				)
			)
		)
		(pad "32" smd custom
			(at -1.400048 -2.4511 90)
			(size 0.0508 0.0508)
			(layers "B.Cu" "B.Mask" "B.Paste")
			(net "PU_VR_PVCCIO_CPU0_FAULT1")
			(options
				(clearance outline)
				(anchor circle)
			)
			(primitives
				(gr_poly
					(pts
						(arc
							(start 0.1016 -0.254)
							(mid 0 -0.3556)
							(end -0.1016 -0.254)
						)
						(xy -0.1016 0.3556) (xy 0.1016 0.3556)
					)
					(width 0)
					(fill yes)
				)
			)
		)
		(pad "33" smd custom
			(at -0.999998 -2.4511 90)
			(size 0.0508 0.0508)
			(layers "B.Cu" "B.Mask" "B.Paste")
			(net "VR_PVCCIO_CPU0_XADDR2")
			(options
				(clearance outline)
				(anchor circle)
			)
			(primitives
				(gr_poly
					(pts
						(arc
							(start 0.1016 -0.254)
							(mid 0 -0.3556)
							(end -0.1016 -0.254)
						)
						(xy -0.1016 0.3556) (xy 0.1016 0.3556)
					)
					(width 0)
					(fill yes)
				)
			)
		)
		(pad "34" smd custom
			(at -0.599948 -2.4511 90)
			(size 0.0508 0.0508)
			(layers "B.Cu" "B.Mask" "B.Paste")
			(net "Net_252")
			(options
				(clearance outline)
				(anchor circle)
			)
			(primitives
				(gr_poly
					(pts
						(arc
							(start 0.1016 -0.254)
							(mid 0 -0.3556)
							(end -0.1016 -0.254)
						)
						(xy -0.1016 0.3556) (xy 0.1016 0.3556)
					)
					(width 0)
					(fill yes)
				)
			)
		)
	)
)
